(kicad_pcb
	(version 20260206)
	(generator "pcbnew")
	(generator_version "10.0")
	(general
		(thickness 1.6)
		(legacy_teardrops no)
	)
	(paper "A4")
	(title_block
		(title "04192023_DAF0TMB3IC0_F0TG_MB_C_brd_V02_OCP.brd")
		(comment 1 "Grand Teton / footprint 4346 of 8354 (U6010), pads 1-111 of 354")
	)
	(layers
		(0 "F.Cu" signal "TOP")
		(4 "In1.Cu" signal "GND")
		(6 "In2.Cu" signal "IN1")
		(8 "In3.Cu" signal "GND1")
		(10 "In4.Cu" signal "IN2")
		(12 "In5.Cu" signal "GND2")
		(14 "In6.Cu" signal "IN3")
		(16 "In7.Cu" signal "GND3")
		(18 "In8.Cu" signal "VCC")
		(20 "In9.Cu" signal "VCC1")
		(22 "In10.Cu" signal "GND4")
		(24 "In11.Cu" signal "IN4")
		(26 "In12.Cu" signal "GND5")
		(28 "In13.Cu" signal "IN5")
		(30 "In14.Cu" signal "GND6")
		(32 "In15.Cu" signal "IN6")
		(34 "In16.Cu" signal "GND7")
		(2 "B.Cu" signal "BOTTOM")
		(9 "F.Adhes" user "F.Adhesive")
		(11 "B.Adhes" user "B.Adhesive")
		(13 "F.Paste" user "Package Geometry/Pastemask Top")
		(15 "B.Paste" user "Package Geometry/Pastemask Bottom")
		(5 "F.SilkS" user "Ref Des/Silkscreen Top")
		(7 "B.SilkS" user "Ref Des/Silkscreen Bottom")
		(1 "F.Mask" user "Board Geometry/Soldermask Top")
		(3 "B.Mask" user "Board Geometry/Soldermask Bottom")
		(17 "Dwgs.User" user "User.Drawings")
		(19 "Cmts.User" user "User.Comments")
		(21 "Eco1.User" user "User.Eco1")
		(23 "Eco2.User" user "User.Eco2")
		(25 "Edge.Cuts" user "Board Geometry/Outline")
		(27 "Margin" user)
		(31 "F.CrtYd" user "Package Geometry/Place Bound Top")
		(29 "B.CrtYd" user "Package Geometry/Place Bound Bottom")
		(35 "F.Fab" user "Ref Des/Assembly Top")
		(33 "B.Fab" user "Ref Des/Assembly Bottom")
	)
	(footprint ""
		(layer "F.Cu")
		(at 312.467752 -395.724634)
		(property "Reference" "U6010"
			(at -6.426454 -7.380224 0)
			(unlocked yes)
			(layer "F.SilkS")
			(effects
				(font
					(size 0.7874 0.5842)
					(thickness 0.1524)
				)
				(justify left)
			)
		)
		(property "Value" ""
			(at 0 0 0)
			(layer "F.Fab")
			(effects
				(font
					(size 1.27 1.27)
				)
			)
		)
		(duplicate_pad_numbers_are_jumpers no)
		(pad "A1" smd oval
			(at 11.050016 -3.938524)
			(size 0.254 0.3302)
			(layers "F.Cu" "F.Mask" "F.Paste")
			(net "NCF_A1_CPU0_P0_GND")
		)
		(pad "A35" smd oval
			(at 11.050016 3.940048)
			(size 0.254 0.3302)
			(layers "F.Cu" "F.Mask" "F.Paste")
			(net "NCF_CPU0_P0_GND")
		)
		(pad "AA10" smd circle
			(at 7.602728 -1.431798)
			(size 0.381 0.381)
			(layers "F.Cu" "F.Mask" "F.Paste")
			(net "P5E_CPU0_P0_TX_BUF_DN<14>")
		)
		(pad "AA29" smd circle
			(at 7.602728 2.032254)
			(size 0.381 0.381)
			(layers "F.Cu" "F.Mask" "F.Paste")
			(net "P5E_CPU0_P0_RX_DN<14>")
		)
		(pad "AB1" smd oval
			(at 7.450074 -3.938524)
			(size 0.254 0.3302)
			(layers "F.Cu" "F.Mask" "F.Paste")
			(net "P5E_CPU0_P0_RX_BUF_DP<14>")
		)
		(pad "AB35" smd oval
			(at 7.450074 3.940048)
			(size 0.254 0.3302)
			(layers "F.Cu" "F.Mask" "F.Paste")
			(net "P5E_CPU0_P0_TX_C_DP<14>")
		)
		(pad "AC4" smd circle
			(at 7.202678 -2.817368)
			(size 0.381 0.381)
			(layers "F.Cu" "F.Mask" "F.Paste")
			(net "GND")
		)
		(pad "AC13" smd circle
			(at 7.202678 -0.79629)
			(size 0.3048 0.3048)
			(layers "F.Cu" "F.Mask" "F.Paste")
			(net "GND")
		)
		(pad "AC17" smd circle
			(at 7.202678 -0.296164)
			(size 0.3048 0.3048)
			(layers "F.Cu" "F.Mask" "F.Paste")
			(net "P0V9_CPU0_RT0_2A")
		)
		(pad "AC20" smd circle
			(at 7.202678 0.203708)
			(size 0.3048 0.3048)
			(layers "F.Cu" "F.Mask" "F.Paste")
			(net "P0V9_CPU0_RT0_2A")
		)
		(pad "AC22" smd circle
			(at 7.202678 0.703834)
			(size 0.3048 0.3048)
			(layers "F.Cu" "F.Mask" "F.Paste")
			(net "GND")
		)
		(pad "AC32" smd circle
			(at 7.202678 2.724912)
			(size 0.381 0.381)
			(layers "F.Cu" "F.Mask" "F.Paste")
			(net "GND")
		)
		(pad "AD2" smd circle
			(at 7.1501 -3.41884)
			(size 0.3048 0.3048)
			(layers "F.Cu" "F.Mask" "F.Paste")
			(net "GND")
		)
		(pad "AD34" smd circle
			(at 7.1501 3.420364)
			(size 0.3048 0.3048)
			(layers "F.Cu" "F.Mask" "F.Paste")
			(net "GND")
		)
		(pad "AE1" smd oval
			(at 6.849872 -3.938524)
			(size 0.254 0.3302)
			(layers "F.Cu" "F.Mask" "F.Paste")
			(net "GND")
		)
		(pad "AE35" smd oval
			(at 6.849872 3.940048)
			(size 0.254 0.3302)
			(layers "F.Cu" "F.Mask" "F.Paste")
			(net "GND")
		)
		(pad "AF7" smd circle
			(at 6.802628 -2.12471)
			(size 0.381 0.381)
			(layers "F.Cu" "F.Mask" "F.Paste")
			(net "P5E_CPU0_P0_TX_BUF_DP<13>")
		)
		(pad "AF26" smd circle
			(at 6.802628 1.339342)
			(size 0.381 0.381)
			(layers "F.Cu" "F.Mask" "F.Paste")
			(net "P5E_CPU0_P0_RX_DP<13>")
		)
		(pad "AG2" smd circle
			(at 6.549898 -3.41884)
			(size 0.3048 0.3048)
			(layers "F.Cu" "F.Mask" "F.Paste")
			(net "P5E_CPU0_P0_RX_BUF_DN<13>")
		)
		(pad "AG34" smd circle
			(at 6.549898 3.420364)
			(size 0.3048 0.3048)
			(layers "F.Cu" "F.Mask" "F.Paste")
			(net "P5E_CPU0_P0_TX_C_DP<13>")
		)
		(pad "AH10" smd circle
			(at 6.402578 -1.431798)
			(size 0.381 0.381)
			(layers "F.Cu" "F.Mask" "F.Paste")
			(net "P5E_CPU0_P0_TX_BUF_DN<13>")
		)
		(pad "AH29" smd circle
			(at 6.402578 2.032254)
			(size 0.381 0.381)
			(layers "F.Cu" "F.Mask" "F.Paste")
			(net "P5E_CPU0_P0_RX_DN<13>")
		)
		(pad "AJ1" smd oval
			(at 6.249924 -3.938524)
			(size 0.254 0.3302)
			(layers "F.Cu" "F.Mask" "F.Paste")
			(net "P5E_CPU0_P0_RX_BUF_DP<13>")
		)
		(pad "AJ35" smd oval
			(at 6.249924 3.940048)
			(size 0.254 0.3302)
			(layers "F.Cu" "F.Mask" "F.Paste")
			(net "P5E_CPU0_P0_TX_C_DN<13>")
		)
		(pad "AK4" smd circle
			(at 6.002528 -2.817368)
			(size 0.381 0.381)
			(layers "F.Cu" "F.Mask" "F.Paste")
			(net "GND")
		)
		(pad "AK13" smd circle
			(at 6.002528 -0.79629)
			(size 0.3048 0.3048)
			(layers "F.Cu" "F.Mask" "F.Paste")
			(net "GND")
		)
		(pad "AK17" smd circle
			(at 6.002528 -0.296164)
			(size 0.3048 0.3048)
			(layers "F.Cu" "F.Mask" "F.Paste")
			(net "P0V9_CPU0_RT0_2A")
		)
		(pad "AK20" smd circle
			(at 6.002528 0.203708)
			(size 0.3048 0.3048)
			(layers "F.Cu" "F.Mask" "F.Paste")
			(net "P0V9_CPU0_RT0_2A")
		)
		(pad "AK22" smd circle
			(at 6.002528 0.703834)
			(size 0.3048 0.3048)
			(layers "F.Cu" "F.Mask" "F.Paste")
			(net "GND")
		)
		(pad "AK32" smd circle
			(at 6.002528 2.724912)
			(size 0.381 0.381)
			(layers "F.Cu" "F.Mask" "F.Paste")
			(net "GND")
		)
		(pad "AL2" smd circle
			(at 5.94995 -3.41884)
			(size 0.3048 0.3048)
			(layers "F.Cu" "F.Mask" "F.Paste")
			(net "GND")
		)
		(pad "AL34" smd circle
			(at 5.94995 3.420364)
			(size 0.3048 0.3048)
			(layers "F.Cu" "F.Mask" "F.Paste")
			(net "GND")
		)
		(pad "AM1" smd oval
			(at 5.649976 -3.938524)
			(size 0.254 0.3302)
			(layers "F.Cu" "F.Mask" "F.Paste")
			(net "GND")
		)
		(pad "AM35" smd oval
			(at 5.649976 3.940048)
			(size 0.254 0.3302)
			(layers "F.Cu" "F.Mask" "F.Paste")
			(net "GND")
		)
		(pad "AN7" smd circle
			(at 5.602478 -2.12471)
			(size 0.381 0.381)
			(layers "F.Cu" "F.Mask" "F.Paste")
			(net "P5E_CPU0_P0_TX_BUF_DP<12>")
		)
		(pad "AN26" smd circle
			(at 5.602478 1.339342)
			(size 0.381 0.381)
			(layers "F.Cu" "F.Mask" "F.Paste")
			(net "P5E_CPU0_P0_RX_DP<12>")
		)
		(pad "AP2" smd circle
			(at 5.350002 -3.41884)
			(size 0.3048 0.3048)
			(layers "F.Cu" "F.Mask" "F.Paste")
			(net "P5E_CPU0_P0_RX_BUF_DN<12>")
		)
		(pad "AP34" smd circle
			(at 5.350002 3.420364)
			(size 0.3048 0.3048)
			(layers "F.Cu" "F.Mask" "F.Paste")
			(net "P5E_CPU0_P0_TX_C_DN<12>")
		)
		(pad "AR10" smd circle
			(at 5.202682 -1.431798)
			(size 0.381 0.381)
			(layers "F.Cu" "F.Mask" "F.Paste")
			(net "P5E_CPU0_P0_TX_BUF_DN<12>")
		)
		(pad "AR29" smd circle
			(at 5.202682 2.032254)
			(size 0.381 0.381)
			(layers "F.Cu" "F.Mask" "F.Paste")
			(net "P5E_CPU0_P0_RX_DN<12>")
		)
		(pad "AT1" smd oval
			(at 5.050028 -3.938524)
			(size 0.254 0.3302)
			(layers "F.Cu" "F.Mask" "F.Paste")
			(net "P5E_CPU0_P0_RX_BUF_DP<12>")
		)
		(pad "AT35" smd oval
			(at 5.050028 3.940048)
			(size 0.254 0.3302)
			(layers "F.Cu" "F.Mask" "F.Paste")
			(net "P5E_CPU0_P0_TX_C_DP<12>")
		)
		(pad "AU4" smd circle
			(at 4.802632 -2.817368)
			(size 0.381 0.381)
			(layers "F.Cu" "F.Mask" "F.Paste")
			(net "GND")
		)
		(pad "AU13" smd circle
			(at 4.802632 -0.79629)
			(size 0.3048 0.3048)
			(layers "F.Cu" "F.Mask" "F.Paste")
			(net "GND")
		)
		(pad "AU17" smd circle
			(at 4.802632 -0.296164)
			(size 0.3048 0.3048)
			(layers "F.Cu" "F.Mask" "F.Paste")
			(net "P0V9_CPU0_RT0_2A")
		)
		(pad "AU20" smd circle
			(at 4.802632 0.203708)
			(size 0.3048 0.3048)
			(layers "F.Cu" "F.Mask" "F.Paste")
			(net "P0V9_CPU0_RT0_2A")
		)
		(pad "AU22" smd circle
			(at 4.802632 0.703834)
			(size 0.3048 0.3048)
			(layers "F.Cu" "F.Mask" "F.Paste")
			(net "GND")
		)
		(pad "AU32" smd circle
			(at 4.802632 2.724912)
			(size 0.381 0.381)
			(layers "F.Cu" "F.Mask" "F.Paste")
			(net "GND")
		)
		(pad "AV2" smd circle
			(at 4.750054 -3.41884)
			(size 0.3048 0.3048)
			(layers "F.Cu" "F.Mask" "F.Paste")
			(net "GND")
		)
		(pad "AV34" smd circle
			(at 4.750054 3.420364)
			(size 0.3048 0.3048)
			(layers "F.Cu" "F.Mask" "F.Paste")
			(net "GND")
		)
		(pad "AW1" smd oval
			(at 4.45008 -3.938524)
			(size 0.254 0.3302)
			(layers "F.Cu" "F.Mask" "F.Paste")
			(net "GND")
		)
		(pad "AW35" smd oval
			(at 4.45008 3.940048)
			(size 0.254 0.3302)
			(layers "F.Cu" "F.Mask" "F.Paste")
			(net "GND")
		)
		(pad "AY7" smd circle
			(at 4.402582 -2.12471)
			(size 0.381 0.381)
			(layers "F.Cu" "F.Mask" "F.Paste")
			(net "P5E_CPU0_P0_TX_BUF_DP<11>")
		)
		(pad "AY26" smd circle
			(at 4.402582 1.339342)
			(size 0.381 0.381)
			(layers "F.Cu" "F.Mask" "F.Paste")
			(net "P5E_CPU0_P0_RX_DP<11>")
		)
		(pad "B3" smd oval
			(at 10.885932 -2.888488 90)
			(size 0.254 0.3302)
			(layers "F.Cu" "F.Mask" "F.Paste")
			(net "JTAG_TCK_RT_CPU0_P0")
		)
		(pad "B6" smd oval
			(at 10.885932 -2.288286 90)
			(size 0.254 0.3302)
			(layers "F.Cu" "F.Mask" "F.Paste")
			(net "JTAG_TDI_RT_CPU0_P0")
		)
		(pad "B9" smd oval
			(at 10.885932 -1.688338 90)
			(size 0.254 0.3302)
			(layers "F.Cu" "F.Mask" "F.Paste")
			(net "JTAG_TDO_RT_CPU0_P0")
		)
		(pad "B12" smd oval
			(at 10.885932 -1.08839 90)
			(size 0.254 0.3302)
			(layers "F.Cu" "F.Mask" "F.Paste")
			(net "JTAG_TMS_RT_CPU0_P0")
		)
		(pad "B16" smd oval
			(at 10.885932 -0.488442 90)
			(size 0.254 0.3302)
			(layers "F.Cu" "F.Mask" "F.Paste")
			(net "Net_2203")
		)
		(pad "B19" smd oval
			(at 10.885932 0.111506 90)
			(size 0.254 0.3302)
			(layers "F.Cu" "F.Mask" "F.Paste")
			(net "GND")
		)
		(pad "B23" smd oval
			(at 10.885932 0.711708 90)
			(size 0.254 0.3302)
			(layers "F.Cu" "F.Mask" "F.Paste")
			(net "RT_CPU0_P0_ADDR2")
		)
		(pad "B25" smd oval
			(at 10.885932 1.311656 90)
			(size 0.254 0.3302)
			(layers "F.Cu" "F.Mask" "F.Paste")
			(net "RT_CPU0_P0_ADDR3")
		)
		(pad "B28" smd oval
			(at 10.885932 1.911604 90)
			(size 0.254 0.3302)
			(layers "F.Cu" "F.Mask" "F.Paste")
			(net "SMB_RT_CPU0_P0_R2_SDA")
		)
		(pad "B31" smd oval
			(at 10.885932 2.511552 90)
			(size 0.254 0.3302)
			(layers "F.Cu" "F.Mask" "F.Paste")
			(net "SMB_RT_CPU0_P0_R2_SCL")
		)
		(pad "BA2" smd circle
			(at 4.150106 -3.41884)
			(size 0.3048 0.3048)
			(layers "F.Cu" "F.Mask" "F.Paste")
			(net "P5E_CPU0_P0_RX_BUF_DN<11>")
		)
		(pad "BA34" smd circle
			(at 4.150106 3.420364)
			(size 0.3048 0.3048)
			(layers "F.Cu" "F.Mask" "F.Paste")
			(net "P5E_CPU0_P0_TX_C_DN<11>")
		)
		(pad "BB10" smd circle
			(at 4.002532 -1.431798)
			(size 0.381 0.381)
			(layers "F.Cu" "F.Mask" "F.Paste")
			(net "P5E_CPU0_P0_TX_BUF_DN<11>")
		)
		(pad "BB29" smd circle
			(at 4.002532 2.032254)
			(size 0.381 0.381)
			(layers "F.Cu" "F.Mask" "F.Paste")
			(net "P5E_CPU0_P0_RX_DN<11>")
		)
		(pad "BC1" smd oval
			(at 3.849878 -3.938524)
			(size 0.254 0.3302)
			(layers "F.Cu" "F.Mask" "F.Paste")
			(net "P5E_CPU0_P0_RX_BUF_DP<11>")
		)
		(pad "BC35" smd oval
			(at 3.849878 3.940048)
			(size 0.254 0.3302)
			(layers "F.Cu" "F.Mask" "F.Paste")
			(net "P5E_CPU0_P0_TX_C_DP<11>")
		)
		(pad "BD4" smd circle
			(at 3.602482 -2.817368)
			(size 0.381 0.381)
			(layers "F.Cu" "F.Mask" "F.Paste")
			(net "GND")
		)
		(pad "BD13" smd circle
			(at 3.602482 -0.79629)
			(size 0.3048 0.3048)
			(layers "F.Cu" "F.Mask" "F.Paste")
			(net "GND")
		)
		(pad "BD17" smd circle
			(at 3.602482 -0.296164)
			(size 0.3048 0.3048)
			(layers "F.Cu" "F.Mask" "F.Paste")
			(net "P0V9_CPU0_RT0_2A_2D")
		)
		(pad "BD20" smd circle
			(at 3.602482 0.203708)
			(size 0.3048 0.3048)
			(layers "F.Cu" "F.Mask" "F.Paste")
			(net "P0V9_CPU0_RT0_2A_2D")
		)
		(pad "BD22" smd circle
			(at 3.602482 0.703834)
			(size 0.3048 0.3048)
			(layers "F.Cu" "F.Mask" "F.Paste")
			(net "GND")
		)
		(pad "BD32" smd circle
			(at 3.602482 2.724912)
			(size 0.381 0.381)
			(layers "F.Cu" "F.Mask" "F.Paste")
			(net "GND")
		)
		(pad "BE2" smd circle
			(at 3.549904 -3.41884)
			(size 0.3048 0.3048)
			(layers "F.Cu" "F.Mask" "F.Paste")
			(net "GND")
		)
		(pad "BE34" smd circle
			(at 3.549904 3.420364)
			(size 0.3048 0.3048)
			(layers "F.Cu" "F.Mask" "F.Paste")
			(net "GND")
		)
		(pad "BF1" smd oval
			(at 3.24993 -3.938524)
			(size 0.254 0.3302)
			(layers "F.Cu" "F.Mask" "F.Paste")
			(net "GND")
		)
		(pad "BF35" smd oval
			(at 3.24993 3.940048)
			(size 0.254 0.3302)
			(layers "F.Cu" "F.Mask" "F.Paste")
			(net "GND")
		)
		(pad "BG7" smd circle
			(at 3.202686 -2.12471)
			(size 0.381 0.381)
			(layers "F.Cu" "F.Mask" "F.Paste")
			(net "P5E_CPU0_P0_TX_BUF_DP<10>")
		)
		(pad "BG26" smd circle
			(at 3.202686 1.339342)
			(size 0.381 0.381)
			(layers "F.Cu" "F.Mask" "F.Paste")
			(net "P5E_CPU0_P0_RX_DP<10>")
		)
		(pad "BH2" smd circle
			(at 2.949956 -3.41884)
			(size 0.3048 0.3048)
			(layers "F.Cu" "F.Mask" "F.Paste")
			(net "P5E_CPU0_P0_RX_BUF_DN<10>")
		)
		(pad "BH34" smd circle
			(at 2.949956 3.420364)
			(size 0.3048 0.3048)
			(layers "F.Cu" "F.Mask" "F.Paste")
			(net "P5E_CPU0_P0_TX_C_DN<10>")
		)
		(pad "BJ10" smd circle
			(at 2.802636 -1.431798)
			(size 0.381 0.381)
			(layers "F.Cu" "F.Mask" "F.Paste")
			(net "P5E_CPU0_P0_TX_BUF_DN<10>")
		)
		(pad "BJ29" smd circle
			(at 2.802636 2.032254)
			(size 0.381 0.381)
			(layers "F.Cu" "F.Mask" "F.Paste")
			(net "P5E_CPU0_P0_RX_DN<10>")
		)
		(pad "BK1" smd oval
			(at 2.649982 -3.938524)
			(size 0.254 0.3302)
			(layers "F.Cu" "F.Mask" "F.Paste")
			(net "P5E_CPU0_P0_RX_BUF_DP<10>")
		)
		(pad "BK35" smd oval
			(at 2.649982 3.940048)
			(size 0.254 0.3302)
			(layers "F.Cu" "F.Mask" "F.Paste")
			(net "P5E_CPU0_P0_TX_C_DP<10>")
		)
		(pad "BL4" smd circle
			(at 2.402586 -2.817368)
			(size 0.381 0.381)
			(layers "F.Cu" "F.Mask" "F.Paste")
			(net "GND")
		)
		(pad "BL13" smd circle
			(at 2.402586 -0.79629)
			(size 0.3048 0.3048)
			(layers "F.Cu" "F.Mask" "F.Paste")
			(net "GND")
		)
		(pad "BL17" smd circle
			(at 2.402586 -0.296164)
			(size 0.3048 0.3048)
			(layers "F.Cu" "F.Mask" "F.Paste")
			(net "P0V9_CPU0_RT_2D")
		)
		(pad "BL20" smd circle
			(at 2.402586 0.203708)
			(size 0.3048 0.3048)
			(layers "F.Cu" "F.Mask" "F.Paste")
			(net "P0V9_CPU0_RT_2D")
		)
		(pad "BL22" smd circle
			(at 2.402586 0.703834)
			(size 0.3048 0.3048)
			(layers "F.Cu" "F.Mask" "F.Paste")
			(net "GND")
		)
		(pad "BL32" smd circle
			(at 2.402586 2.724912)
			(size 0.381 0.381)
			(layers "F.Cu" "F.Mask" "F.Paste")
			(net "GND")
		)
		(pad "BM2" smd circle
			(at 2.350008 -3.41884)
			(size 0.3048 0.3048)
			(layers "F.Cu" "F.Mask" "F.Paste")
			(net "GND")
		)
		(pad "BM34" smd circle
			(at 2.350008 3.420364)
			(size 0.3048 0.3048)
			(layers "F.Cu" "F.Mask" "F.Paste")
			(net "GND")
		)
		(pad "BN1" smd oval
			(at 2.050034 -3.938524)
			(size 0.254 0.3302)
			(layers "F.Cu" "F.Mask" "F.Paste")
			(net "GND")
		)
		(pad "BN35" smd oval
			(at 2.050034 3.940048)
			(size 0.254 0.3302)
			(layers "F.Cu" "F.Mask" "F.Paste")
			(net "GND")
		)
		(pad "BP7" smd circle
			(at 2.002536 -2.12471)
			(size 0.381 0.381)
			(layers "F.Cu" "F.Mask" "F.Paste")
			(net "P5E_CPU0_P0_TX_BUF_DP<9>")
		)
		(pad "BP26" smd circle
			(at 2.002536 1.339342)
			(size 0.381 0.381)
			(layers "F.Cu" "F.Mask" "F.Paste")
			(net "P5E_CPU0_P0_RX_DP<9>")
		)
		(pad "BR2" smd circle
			(at 1.75006 -3.41884)
			(size 0.3048 0.3048)
			(layers "F.Cu" "F.Mask" "F.Paste")
			(net "P5E_CPU0_P0_RX_BUF_DN<9>")
		)
		(pad "BR34" smd circle
			(at 1.75006 3.420364)
			(size 0.3048 0.3048)
			(layers "F.Cu" "F.Mask" "F.Paste")
			(net "P5E_CPU0_P0_TX_C_DN<9>")
		)
		(pad "BT10" smd circle
			(at 1.602486 -1.431798)
			(size 0.381 0.381)
			(layers "F.Cu" "F.Mask" "F.Paste")
			(net "P5E_CPU0_P0_TX_BUF_DN<9>")
		)
		(pad "BT29" smd circle
			(at 1.602486 2.032254)
			(size 0.381 0.381)
			(layers "F.Cu" "F.Mask" "F.Paste")
			(net "P5E_CPU0_P0_RX_DN<9>")
		)
		(pad "BU1" smd oval
			(at 1.450086 -3.938524)
			(size 0.254 0.3302)
			(layers "F.Cu" "F.Mask" "F.Paste")
			(net "P5E_CPU0_P0_RX_BUF_DP<9>")
		)
		(pad "BU35" smd oval
			(at 1.450086 3.940048)
			(size 0.254 0.3302)
			(layers "F.Cu" "F.Mask" "F.Paste")
			(net "P5E_CPU0_P0_TX_C_DP<9>")
		)
		(pad "BV4" smd circle
			(at 1.20269 -2.817368)
			(size 0.381 0.381)
			(layers "F.Cu" "F.Mask" "F.Paste")
			(net "GND")
		)
		(pad "BV13" smd circle
			(at 1.20269 -0.79629)
			(size 0.3048 0.3048)
			(layers "F.Cu" "F.Mask" "F.Paste")
			(net "GND")
		)
		(pad "BV17" smd circle
			(at 1.20269 -0.296164)
			(size 0.3048 0.3048)
			(layers "F.Cu" "F.Mask" "F.Paste")
			(net "P1V8_CPU0_RT0_1A_1D")
		)
		(pad "BV20" smd circle
			(at 1.20269 0.203708)
			(size 0.3048 0.3048)
			(layers "F.Cu" "F.Mask" "F.Paste")
			(net "P1V8_CPU0_RT0_1A")
		)
		(pad "BV22" smd circle
			(at 1.20269 0.703834)
			(size 0.3048 0.3048)
			(layers "F.Cu" "F.Mask" "F.Paste")
			(net "GND")
		)
	)
)
